# BASEBOARD_FAB2 (Tioga Pass) — schematic netlist excerpt (pin names and nets, part order shuffled) for the footprints in the layout excerpt that follows; sources: Cadence DE-HDL packaged netlist, KiCad conversion of Wiwynn_Tioga_Pass_MB.brd

C9P6  CAP_A  0.1UF 16V 10% X7R  pkg 0402V  page 200 : A = P12V_STBY ; B = AGND_HSC

Q6W4  FET_N  2N7002 FET  pkg SOT23LF  page 168
  GATE  = DEBUG_CARD2_PRSNT
  SRC  = GND
  DRN  = FM_POST_CARD_PRES_BMC_N

C2T12  CAP_A  0.1UF 16V 10% X7R  pkg 0402V  page 154 : A = P3V3_STBY ; B = GND

(kicad_pcb
	(version 20260206)
	(generator "pcbnew")
	(generator_version "10.0")
	(general
		(thickness 1.6)
		(legacy_teardrops no)
	)
	(paper "A4")
	(title_block
		(title "Wiwynn_Tioga_Pass_MB.brd")
		(comment 1 "Tioga Pass / footprints 2810-2812 of 4770")
	)
	(layers
		(0 "F.Cu" signal "TOP")
		(4 "In1.Cu" signal "L2GND")
		(6 "In2.Cu" signal "L3")
		(8 "In3.Cu" signal "L4GND")
		(10 "In4.Cu" signal "L5")
		(12 "In5.Cu" signal "L6GND")
		(14 "In6.Cu" signal "L7VCC")
		(16 "In7.Cu" signal "L8VCC")
		(18 "In8.Cu" signal "L9GND")
		(20 "In9.Cu" signal "L10")
		(22 "In10.Cu" signal "L11GND")
		(24 "In11.Cu" signal "L12")
		(26 "In12.Cu" signal "L13GND")
		(2 "B.Cu" signal "BOTTOM")
		(9 "F.Adhes" user "F.Adhesive")
		(11 "B.Adhes" user "B.Adhesive")
		(13 "F.Paste" user "Package Geometry/Pastemask Top")
		(15 "B.Paste" user "Package Geometry/Pastemask Bottom")
		(5 "F.SilkS" user "Ref Des/Silkscreen Top")
		(7 "B.SilkS" user "Ref Des/Silkscreen Bottom")
		(1 "F.Mask" user "Board Geometry/Soldermask Top")
		(3 "B.Mask" user "Board Geometry/Soldermask Bottom")
		(17 "Dwgs.User" user "User.Drawings")
		(19 "Cmts.User" user "User.Comments")
		(21 "Eco1.User" user "User.Eco1")
		(23 "Eco2.User" user "User.Eco2")
		(25 "Edge.Cuts" user "Board Geometry/Outline")
		(27 "Margin" user)
		(31 "F.CrtYd" user "Package Geometry/Place Bound Top")
		(29 "B.CrtYd" user "Package Geometry/Place Bound Bottom")
		(35 "F.Fab" user "Ref Des/Assembly Top")
		(33 "B.Fab" user "Ref Des/Assembly Bottom")
	)
	(footprint ""
		(layer "B.Cu")
		(at 494.665 -135.2804 -90)
		(property "Reference" "Q6W4"
			(at 0.229362 -1.59512 270)
			(unlocked yes)
			(layer "B.SilkS")
			(effects
				(font
					(size 1.27 0.9652)
					(thickness 0.1524)
				)
				(justify left mirror)
			)
		)
		(property "Value" ""
			(at 0 0 90)
			(layer "B.Fab")
			(effects
				(font
					(size 1.27 1.27)
				)
				(justify mirror)
			)
		)
		(duplicate_pad_numbers_are_jumpers no)
		(fp_line
			(start -1.778 2.4765)
			(end -1.778 1.5875)
			(stroke
				(width 0.1524)
				(type default)
			)
			(layer "B.SilkS")
		)
		(fp_line
			(start -0.9525 2.4765)
			(end -1.778 2.4765)
			(stroke
				(width 0.1524)
				(type default)
			)
			(layer "B.SilkS")
		)
		(fp_line
			(start -0.381 0.635)
			(end -0.381 1.27)
			(stroke
				(width 0.1524)
				(type default)
			)
			(layer "B.SilkS")
		)
		(fp_line
			(start -1.778 -0.5715)
			(end -1.778 0.3175)
			(stroke
				(width 0.1524)
				(type default)
			)
			(layer "B.SilkS")
		)
		(fp_line
			(start -0.9525 -0.5715)
			(end -1.778 -0.5715)
			(stroke
				(width 0.1524)
				(type default)
			)
			(layer "B.SilkS")
		)
		(fp_circle
			(center 0.51816 -0.82423)
			(end 0.51816 -0.95123)
			(stroke
				(width 0.254)
				(type default)
			)
			(fill no)
			(layer "B.SilkS")
		)
		(fp_poly
			(pts
				(xy -1.778 2.4765) (xy -0.381 2.4765) (xy -0.381 -0.5715) (xy -1.778 -0.5715)
			)
			(stroke
				(width 0)
				(type default)
			)
			(fill no)
			(layer "B.CrtYd")
		)
		(fp_line
			(start -1.778 2.4765)
			(end -1.778 -0.5715)
			(stroke
				(width 0.1)
				(type default)
			)
			(layer "B.Fab")
		)
		(fp_line
			(start -0.381 2.4765)
			(end -1.778 2.4765)
			(stroke
				(width 0.1)
				(type default)
			)
			(layer "B.Fab")
		)
		(fp_line
			(start -1.778 -0.5715)
			(end -0.381 -0.5715)
			(stroke
				(width 0.1)
				(type default)
			)
			(layer "B.Fab")
		)
		(fp_line
			(start -0.381 -0.5715)
			(end -0.381 2.4765)
			(stroke
				(width 0.1)
				(type default)
			)
			(layer "B.Fab")
		)
		(fp_circle
			(center 0.9525 -0.9271)
			(end 0.9525 -1.0541)
			(stroke
				(width 0.254)
				(type default)
			)
			(fill no)
			(layer "B.Fab")
		)
		(pad "1" smd rect
			(at 0 0 90)
			(size 1.143 0.508)
			(layers "B.Cu" "B.Mask" "B.Paste")
			(net "DEBUG_CARD2_PRSNT")
		)
		(pad "2" smd rect
			(at 0 1.905 90)
			(size 1.143 0.508)
			(layers "B.Cu" "B.Mask" "B.Paste")
			(net "GND")
		)
		(pad "3" smd rect
			(at -2.159 0.9525 90)
			(size 1.143 0.508)
			(layers "B.Cu" "B.Mask" "B.Paste")
			(net "FM_POST_CARD_PRES_BMC_N")
		)
	)
	(footprint ""
		(layer "B.Cu")
		(at 22.225 -81.534)
		(property "Reference" "C9P6"
			(at 0 0 0)
			(layer "B.SilkS")
			(hide yes)
			(effects
				(font
					(size 1.27 1.27)
				)
				(justify mirror)
			)
		)
		(property "Value" ""
			(at 0 0 0)
			(layer "B.Fab")
			(effects
				(font
					(size 1.27 1.27)
				)
				(justify mirror)
			)
		)
		(duplicate_pad_numbers_are_jumpers no)
		(fp_poly
			(pts
				(xy -0.3048 -0.1016) (xy -0.3048 0.9906) (xy 0.3048 0.9906) (xy 0.3048 -0.1016)
			)
			(stroke
				(width 0)
				(type default)
			)
			(fill no)
			(layer "B.CrtYd")
		)
		(fp_line
			(start -0.3048 -0.1016)
			(end 0.3048 -0.1016)
			(stroke
				(width 0.1)
				(type default)
			)
			(layer "B.Fab")
		)
		(fp_line
			(start -0.3048 0.9906)
			(end -0.3048 -0.1016)
			(stroke
				(width 0.1)
				(type default)
			)
			(layer "B.Fab")
		)
		(fp_line
			(start 0.3048 -0.1016)
			(end 0.3048 0.9906)
			(stroke
				(width 0.1)
				(type default)
			)
			(layer "B.Fab")
		)
		(fp_line
			(start 0.3048 0.9906)
			(end -0.3048 0.9906)
			(stroke
				(width 0.1)
				(type default)
			)
			(layer "B.Fab")
		)
		(pad "1" smd rect
			(at 0 0 180)
			(size 0.508 0.508)
			(layers "B.Cu" "B.Mask" "B.Paste")
			(net "P12V_STBY")
		)
		(pad "2" smd rect
			(at 0 0.889 180)
			(size 0.508 0.508)
			(layers "B.Cu" "B.Mask" "B.Paste")
			(net "AGND_HSC")
		)
		(zone
			(layer "B.Cu")
			(hatch none 0.5)
			(connect_pads
				(clearance 0)
			)
			(min_thickness 0.25)
			(keepout
				(tracks allowed)
				(vias not_allowed)
				(pads allowed)
				(copperpour not_allowed)
				(footprints allowed)
			)
			(placement
				(enabled no)
				(sheetname "")
			)
			(fill
				(thermal_gap 0.5)
				(thermal_bridge_width 0.5)
				(island_removal_mode 0)
			)
			(polygon
				(pts
					(xy 22.479 -81.28) (xy 21.971 -81.28) (xy 21.971 -80.899) (xy 22.479 -80.899)
				)
			)
		)
		(zone
			(layer "B.Cu")
			(hatch none 0.5)
			(connect_pads
				(clearance 0)
			)
			(min_thickness 0.25)
			(keepout
				(tracks not_allowed)
				(vias allowed)
				(pads allowed)
				(copperpour not_allowed)
				(footprints allowed)
			)
			(placement
				(enabled no)
				(sheetname "")
			)
			(fill
				(thermal_gap 0.5)
				(thermal_bridge_width 0.5)
				(island_removal_mode 0)
			)
			(polygon
				(pts
					(xy 22.479 -80.899) (xy 21.971 -80.899) (xy 21.971 -81.28) (xy 22.479 -81.28)
				)
			)
		)
	)
	(footprint ""
		(layer "B.Cu")
		(at 394.208 -62.738 90)
		(property "Reference" "C2T12"
			(at 0 0 90)
			(layer "B.SilkS")
			(hide yes)
			(effects
				(font
					(size 1.27 1.27)
				)
				(justify mirror)
			)
		)
		(property "Value" ""
			(at 0 0 90)
			(layer "B.Fab")
			(effects
				(font
					(size 1.27 1.27)
				)
				(justify mirror)
			)
		)
		(duplicate_pad_numbers_are_jumpers no)
		(fp_poly
			(pts
				(xy -0.3048 -0.1016) (xy -0.3048 0.9906) (xy 0.3048 0.9906) (xy 0.3048 -0.1016)
			)
			(stroke
				(width 0)
				(type default)
			)
			(fill no)
			(layer "B.CrtYd")
		)
		(fp_line
			(start 0.3048 -0.1016)
			(end 0.3048 0.9906)
			(stroke
				(width 0.1)
				(type default)
			)
			(layer "B.Fab")
		)
		(fp_line
			(start -0.3048 -0.1016)
			(end 0.3048 -0.1016)
			(stroke
				(width 0.1)
				(type default)
			)
			(layer "B.Fab")
		)
		(fp_line
			(start 0.3048 0.9906)
			(end -0.3048 0.9906)
			(stroke
				(width 0.1)
				(type default)
			)
			(layer "B.Fab")
		)
		(fp_line
			(start -0.3048 0.9906)
			(end -0.3048 -0.1016)
			(stroke
				(width 0.1)
				(type default)
			)
			(layer "B.Fab")
		)
		(pad "1" smd rect
			(at 0 0 270)
			(size 0.508 0.508)
			(layers "B.Cu" "B.Mask" "B.Paste")
			(net "P3V3_STBY")
		)
		(pad "2" smd rect
			(at 0 0.889 270)
			(size 0.508 0.508)
			(layers "B.Cu" "B.Mask" "B.Paste")
			(net "GND")
		)
		(zone
			(layer "B.Cu")
			(hatch none 0.5)
			(connect_pads
				(clearance 0)
			)
			(min_thickness 0.25)
			(keepout
				(tracks allowed)
				(vias not_allowed)
				(pads allowed)
				(copperpour not_allowed)
				(footprints allowed)
			)
			(placement
				(enabled no)
				(sheetname "")
			)
			(fill
				(thermal_gap 0.5)
				(thermal_bridge_width 0.5)
				(island_removal_mode 0)
			)
			(polygon
				(pts
					(xy 394.462 -62.992) (xy 394.462 -62.484) (xy 394.843 -62.484) (xy 394.843 -62.992)
				)
			)
		)
		(zone
			(layer "B.Cu")
			(hatch none 0.5)
			(connect_pads
				(clearance 0)
			)
			(min_thickness 0.25)
			(keepout
				(tracks not_allowed)
				(vias allowed)
				(pads allowed)
				(copperpour not_allowed)
				(footprints allowed)
			)
			(placement
				(enabled no)
				(sheetname "")
			)
			(fill
				(thermal_gap 0.5)
				(thermal_bridge_width 0.5)
				(island_removal_mode 0)
			)
			(polygon
				(pts
					(xy 394.843 -62.992) (xy 394.843 -62.484) (xy 394.462 -62.484) (xy 394.462 -62.992)
				)
			)
		)
	)
)
